# T6G (Grand Teton) — schematic netlist excerpt (pin names and nets, part order shuffled) for the footprints in the layout excerpt that follows; sources: Cadence DE-HDL packaged netlist, KiCad conversion of 04192023_DAF0TMB3IC0_F0TG_MB_C_brd_V02_OCP.brd

U13  SN74AUC2G66DCTR  IC  pkg SSOP8  page 174
  \1a\  = JTAG_CPU0_TDO
  \1b\  = JTAG_CPU0_TDO_CPU1_TDI
  \2c\  = FM_PLD_CPU0_PRSNT_HDT_N
  GND  = GND
  \2a\  = JTAG_CPU0_BYPASS_R1
  \2b\  = JTAG_CPU0_TDO_CPU1_TDI_R1
  \1c\  = CPU0_HDT_BYPASS_SEL
  VCC  = PVDD18_S5_P0

(kicad_pcb
	(version 20260206)
	(generator "pcbnew")
	(generator_version "10.0")
	(general
		(thickness 1.6)
		(legacy_teardrops no)
	)
	(paper "A4")
	(title_block
		(title "04192023_DAF0TMB3IC0_F0TG_MB_C_brd_V02_OCP.brd")
		(comment 1 "Grand Teton / footprints 872-872 of 8354")
	)
	(layers
		(0 "F.Cu" signal "TOP")
		(4 "In1.Cu" signal "GND")
		(6 "In2.Cu" signal "IN1")
		(8 "In3.Cu" signal "GND1")
		(10 "In4.Cu" signal "IN2")
		(12 "In5.Cu" signal "GND2")
		(14 "In6.Cu" signal "IN3")
		(16 "In7.Cu" signal "GND3")
		(18 "In8.Cu" signal "VCC")
		(20 "In9.Cu" signal "VCC1")
		(22 "In10.Cu" signal "GND4")
		(24 "In11.Cu" signal "IN4")
		(26 "In12.Cu" signal "GND5")
		(28 "In13.Cu" signal "IN5")
		(30 "In14.Cu" signal "GND6")
		(32 "In15.Cu" signal "IN6")
		(34 "In16.Cu" signal "GND7")
		(2 "B.Cu" signal "BOTTOM")
		(9 "F.Adhes" user "F.Adhesive")
		(11 "B.Adhes" user "B.Adhesive")
		(13 "F.Paste" user "Package Geometry/Pastemask Top")
		(15 "B.Paste" user "Package Geometry/Pastemask Bottom")
		(5 "F.SilkS" user "Ref Des/Silkscreen Top")
		(7 "B.SilkS" user "Ref Des/Silkscreen Bottom")
		(1 "F.Mask" user "Board Geometry/Soldermask Top")
		(3 "B.Mask" user "Board Geometry/Soldermask Bottom")
		(17 "Dwgs.User" user "User.Drawings")
		(19 "Cmts.User" user "User.Comments")
		(21 "Eco1.User" user "User.Eco1")
		(23 "Eco2.User" user "User.Eco2")
		(25 "Edge.Cuts" user "Board Geometry/Outline")
		(27 "Margin" user)
		(31 "F.CrtYd" user "Package Geometry/Place Bound Top")
		(29 "B.CrtYd" user "Package Geometry/Place Bound Bottom")
		(35 "F.Fab" user "Ref Des/Assembly Top")
		(33 "B.Fab" user "Ref Des/Assembly Bottom")
	)
	(footprint ""
		(layer "F.Cu")
		(at 234.739688 -152.631648 180)
		(property "Reference" "U13"
			(at -4.649724 -0.803148 0)
			(unlocked yes)
			(layer "F.SilkS")
			(effects
				(font
					(size 0.7874 0.5842)
					(thickness 0.1524)
				)
				(justify left)
			)
		)
		(property "Value" ""
			(at 0 0 180)
			(layer "F.Fab")
			(effects
				(font
					(size 1.27 1.27)
				)
			)
		)
		(duplicate_pad_numbers_are_jumpers no)
		(fp_line
			(start 1.0414 1.575054)
			(end -1.0414 1.575054)
			(stroke
				(width 0.1524)
				(type default)
			)
			(layer "F.SilkS")
		)
		(fp_line
			(start 1.0414 -1.575054)
			(end 1.0414 1.575054)
			(stroke
				(width 0.1524)
				(type default)
			)
			(layer "F.SilkS")
		)
		(fp_line
			(start 0.254 -1.575054)
			(end 1.0414 -1.575054)
			(stroke
				(width 0.1524)
				(type default)
			)
			(layer "F.SilkS")
		)
		(fp_line
			(start 0.2286 -1.575054)
			(end 0 -1.272032)
			(stroke
				(width 0.1524)
				(type default)
			)
			(layer "F.SilkS")
		)
		(fp_line
			(start 0 -1.272032)
			(end -0.254 -1.575054)
			(stroke
				(width 0.1524)
				(type default)
			)
			(layer "F.SilkS")
		)
		(fp_line
			(start -1.0414 1.575054)
			(end -1.0414 -1.575054)
			(stroke
				(width 0.1524)
				(type default)
			)
			(layer "F.SilkS")
		)
		(fp_line
			(start -1.0414 -1.575054)
			(end -0.254 -1.575054)
			(stroke
				(width 0.1524)
				(type default)
			)
			(layer "F.SilkS")
		)
		(fp_poly
			(pts
				(xy -3.600704 -0.436118) (xy -3.600704 -1.452118) (xy -2.584704 -0.944118)
			)
			(stroke
				(width 0)
				(type default)
			)
			(fill yes)
			(layer "F.SilkS")
		)
		(fp_line
			(start 2.5654 1.2192)
			(end 1.4478 1.2192)
			(stroke
				(width 0.1)
				(type default)
			)
			(layer "F.Fab")
		)
		(fp_line
			(start 2.5654 -1.2192)
			(end 2.5654 1.2192)
			(stroke
				(width 0.1)
				(type default)
			)
			(layer "F.Fab")
		)
		(fp_line
			(start 1.4478 1.5748)
			(end -1.4478 1.5748)
			(stroke
				(width 0.1)
				(type default)
			)
			(layer "F.Fab")
		)
		(fp_line
			(start 1.4478 1.2192)
			(end 1.4478 1.5748)
			(stroke
				(width 0.1)
				(type default)
			)
			(layer "F.Fab")
		)
		(fp_line
			(start 1.4478 -1.2192)
			(end 2.5654 -1.2192)
			(stroke
				(width 0.1)
				(type default)
			)
			(layer "F.Fab")
		)
		(fp_line
			(start 1.4478 -1.5748)
			(end 1.4478 -1.2192)
			(stroke
				(width 0.1)
				(type default)
			)
			(layer "F.Fab")
		)
		(fp_line
			(start -1.4478 1.5748)
			(end -1.4478 1.2192)
			(stroke
				(width 0.1)
				(type default)
			)
			(layer "F.Fab")
		)
		(fp_line
			(start -1.4478 1.2192)
			(end -2.5654 1.2192)
			(stroke
				(width 0.1)
				(type default)
			)
			(layer "F.Fab")
		)
		(fp_line
			(start -1.4478 -1.2192)
			(end -1.4478 -1.5748)
			(stroke
				(width 0.1)
				(type default)
			)
			(layer "F.Fab")
		)
		(fp_line
			(start -1.4478 -1.5748)
			(end 1.4478 -1.5748)
			(stroke
				(width 0.1)
				(type default)
			)
			(layer "F.Fab")
		)
		(fp_line
			(start -2.5654 1.2192)
			(end -2.5654 -1.2192)
			(stroke
				(width 0.1)
				(type default)
			)
			(layer "F.Fab")
		)
		(fp_line
			(start -2.5654 -1.2192)
			(end -1.4478 -1.2192)
			(stroke
				(width 0.1)
				(type default)
			)
			(layer "F.Fab")
		)
		(fp_poly
			(pts
				(xy -2.710688 -0.975106) (xy -3.726688 -1.483106) (xy -3.726688 -0.467106)
			)
			(stroke
				(width 0)
				(type default)
			)
			(fill yes)
			(layer "F.Fab")
		)
		(pad "1" smd rect
			(at -1.849882 -0.975106 90)
			(size 0.3556 1.3208)
			(layers "F.Cu" "F.Mask" "F.Paste")
			(net "JTAG_CPU0_TDO")
		)
		(pad "2" smd rect
			(at -1.849882 -0.32512 90)
			(size 0.3556 1.3208)
			(layers "F.Cu" "F.Mask" "F.Paste")
			(net "JTAG_CPU0_TDO_CPU1_TDI")
		)
		(pad "3" smd rect
			(at -1.849882 0.32512 90)
			(size 0.3556 1.3208)
			(layers "F.Cu" "F.Mask" "F.Paste")
			(net "FM_PLD_CPU0_PRSNT_HDT_N")
		)
		(pad "4" smd rect
			(at -1.849882 0.975106 90)
			(size 0.3556 1.3208)
			(layers "F.Cu" "F.Mask" "F.Paste")
			(net "GND")
		)
		(pad "5" smd rect
			(at 1.849882 0.975106 90)
			(size 0.3556 1.3208)
			(layers "F.Cu" "F.Mask" "F.Paste")
			(net "JTAG_CPU0_BYPASS_R1")
		)
		(pad "6" smd rect
			(at 1.849882 0.32512 90)
			(size 0.3556 1.3208)
			(layers "F.Cu" "F.Mask" "F.Paste")
			(net "JTAG_CPU0_TDO_CPU1_TDI_R1")
		)
		(pad "7" smd rect
			(at 1.849882 -0.32512 90)
			(size 0.3556 1.3208)
			(layers "F.Cu" "F.Mask" "F.Paste")
			(net "CPU0_HDT_BYPASS_SEL")
		)
		(pad "8" smd rect
			(at 1.849882 -0.975106 90)
			(size 0.3556 1.3208)
			(layers "F.Cu" "F.Mask" "F.Paste")
			(net "PVDD18_S5_P0")
		)
	)
)
